(kicad_pcb
	(version 20241229)
	(generator "pcbnew")
	(generator_version "9.0")
	(general
		(thickness 1.6296)
		(legacy_teardrops no)
	)
	(paper "A3")
	(title_block
		(title "Thunderbolt to 10GbE adapter")
		(date "2026-04-21")
		(rev "1.1.0")
		(company "Antmicro Ltd")
		(comment 1 "www.antmicro.com")
		(comment 9 "footprints 68-71 of 703")
	)
	(layers
		(0 "F.Cu" signal)
		(4 "In1.Cu" signal)
		(6 "In2.Cu" signal)
		(8 "In3.Cu" signal)
		(10 "In4.Cu" signal)
		(12 "In5.Cu" signal)
		(14 "In6.Cu" signal)
		(2 "B.Cu" signal)
		(9 "F.Adhes" user "F.Adhesive")
		(11 "B.Adhes" user "B.Adhesive")
		(13 "F.Paste" user)
		(15 "B.Paste" user)
		(5 "F.SilkS" user "F.Silkscreen")
		(7 "B.SilkS" user "B.Silkscreen")
		(1 "F.Mask" user)
		(3 "B.Mask" user)
		(17 "Dwgs.User" user "User.Drawings")
		(19 "Cmts.User" user "User.Comments")
		(21 "Eco1.User" user "User.Eco1")
		(23 "Eco2.User" user "User.Eco2")
		(25 "Edge.Cuts" user)
		(27 "Margin" user)
		(31 "F.CrtYd" user "F.Courtyard")
		(29 "B.CrtYd" user "B.Courtyard")
		(35 "F.Fab" user)
		(33 "B.Fab" user)
	)
	(footprint "antmicro-footprints:LED_0603_1608Metric_G"
		(layer "F.Cu")
		(at 139.5 143.5 90)
		(descr "LED SMD 0603 Green")
		(tags "LED SMD 0603 Green")
		(property "Reference" "D5"
			(at -1 -0.8 90)
			(layer "F.SilkS")
			(effects
				(font
					(size 0.7 0.7)
					(thickness 0.15)
				)
				(justify left bottom)
			)
		)
		(property "Value" "LED_G_0603_KP-1608CGCK"
			(at -0.001 1.599 90)
			(layer "F.Fab")
			(effects
				(font
					(size 0.7 0.7)
					(thickness 0.15)
				)
				(justify left bottom)
			)
		)
		(property "Datasheet" "http://www.kingbright.com/attachments/file/psearch//000/00/00/KP-1608CGCK(Ver.23B).pdf"
			(at 0 0 90)
			(layer "F.Fab")
			(hide yes)
			(effects
				(font
					(size 1.27 1.27)
					(thickness 0.15)
				)
			)
		)
		(property "Description" "LED, Green, SMD, 0603, 20 mA, 2.1 V, 570 nm"
			(at 0 0 90)
			(layer "F.Fab")
			(hide yes)
			(effects
				(font
					(size 1.27 1.27)
					(thickness 0.15)
				)
			)
		)
		(property "MPN" "KP-1608CGCK"
			(at 0 0 90)
			(unlocked yes)
			(layer "F.Fab")
			(hide yes)
			(effects
				(font
					(size 1 1)
					(thickness 0.15)
				)
			)
		)
		(property "Manufacturer" "Kingbright"
			(at 0 0 90)
			(unlocked yes)
			(layer "F.Fab")
			(hide yes)
			(effects
				(font
					(size 1 1)
					(thickness 0.15)
				)
			)
		)
		(property "License" "Apache-2.0"
			(at 0 0 90)
			(unlocked yes)
			(layer "F.Fab")
			(hide yes)
			(effects
				(font
					(size 1 1)
					(thickness 0.15)
				)
			)
		)
		(property "Author" "Antmicro"
			(at 0 0 90)
			(unlocked yes)
			(layer "F.Fab")
			(hide yes)
			(effects
				(font
					(size 1 1)
					(thickness 0.15)
				)
			)
		)
		(property "Color" "Green"
			(at 0 0 90)
			(unlocked yes)
			(layer "F.Fab")
			(hide yes)
			(effects
				(font
					(size 1 1)
					(thickness 0.15)
				)
			)
		)
		(sheetname "/TB Controller - Power/")
		(sheetfile "tb-power.kicad_sch")
		(attr smd)
		(fp_line
			(start 0.22 -0.35)
			(end -0.22 -0.35)
			(stroke
				(width 0.15)
				(type solid)
			)
			(layer "F.SilkS")
		)
		(fp_line
			(start -1.18 -0.319)
			(end -1.18 0.321)
			(stroke
				(width 0.15)
				(type solid)
			)
			(layer "F.SilkS")
		)
		(fp_line
			(start 0.105328 0.001008)
			(end 0.24 0.001)
			(stroke
				(width 0.1)
				(type solid)
			)
			(layer "F.SilkS")
		)
		(fp_line
			(start -0.094672 0.001008)
			(end 0.105328 -0.198992)
			(stroke
				(width 0.1)
				(type solid)
			)
			(layer "F.SilkS")
		)
		(fp_line
			(start -0.094672 0.001008)
			(end -0.24 0.001008)
			(stroke
				(width 0.1)
				(type solid)
			)
			(layer "F.SilkS")
		)
		(fp_line
			(start 0.105328 0.201008)
			(end 0.105328 -0.198992)
			(stroke
				(width 0.1)
				(type solid)
			)
			(layer "F.SilkS")
		)
		(fp_line
			(start 0.105328 0.201008)
			(end -0.094672 0.001008)
			(stroke
				(width 0.1)
				(type solid)
			)
			(layer "F.SilkS")
		)
		(fp_line
			(start -0.094672 0.201008)
			(end -0.094672 -0.198992)
			(stroke
				(width 0.1)
				(type solid)
			)
			(layer "F.SilkS")
		)
		(fp_line
			(start 0.22 0.35)
			(end -0.22 0.35)
			(stroke
				(width 0.15)
				(type solid)
			)
			(layer "F.SilkS")
		)
		(fp_rect
			(start 1.25 0.65)
			(end -1.25 -0.65)
			(stroke
				(width 0.05)
				(type solid)
			)
			(fill no)
			(layer "F.CrtYd")
		)
		(fp_line
			(start 0.201 -0.202)
			(end -0.101 0)
			(stroke
				(width 0.15)
				(type solid)
			)
			(layer "F.Fab")
		)
		(fp_line
			(start -0.199 -0.202)
			(end -0.199 0.1)
			(stroke
				(width 0.15)
				(type solid)
			)
			(layer "F.Fab")
		)
		(fp_line
			(start 0.599 0)
			(end 0.201 0)
			(stroke
				(width 0.15)
				(type solid)
			)
			(layer "F.Fab")
		)
		(fp_line
			(start 0.201 0)
			(end 0.201 -0.202)
			(stroke
				(width 0.15)
				(type solid)
			)
			(layer "F.Fab")
		)
		(fp_line
			(start -0.101 0)
			(end 0.201 0.2)
			(stroke
				(width 0.15)
				(type solid)
			)
			(layer "F.Fab")
		)
		(fp_line
			(start -0.199 0)
			(end -0.597 0)
			(stroke
				(width 0.15)
				(type solid)
			)
			(layer "F.Fab")
		)
		(fp_line
			(start 0.201 0.2)
			(end 0.201 0)
			(stroke
				(width 0.15)
				(type solid)
			)
			(layer "F.Fab")
		)
		(fp_line
			(start -0.199 0.2)
			(end -0.199 0.1)
			(stroke
				(width 0.15)
				(type solid)
			)
			(layer "F.Fab")
		)
		(fp_rect
			(start 0.848 0.4)
			(end -0.85 -0.402)
			(stroke
				(width 0.15)
				(type solid)
			)
			(fill no)
			(layer "F.Fab")
		)
		(fp_text user "Author: Antmicro"
			(at -1.4224 4.799 90)
			(layer "F.Fab")
			(effects
				(font
					(size 0.7 0.7)
					(thickness 0.15)
				)
				(justify left bottom)
			)
		)
		(fp_text user "${REFERENCE}"
			(at -1.4224 5.999 90)
			(layer "F.Fab")
			(effects
				(font
					(size 0.7 0.7)
					(thickness 0.15)
				)
				(justify left bottom)
			)
		)
		(fp_text user "License: Apache-2.0"
			(at -1.4224 3.599 90)
			(layer "F.Fab")
			(effects
				(font
					(size 0.7 0.7)
					(thickness 0.15)
				)
				(justify left bottom)
			)
		)
		(pad "1" smd roundrect
			(at -0.7 0 270)
			(size 0.8 1)
			(layers "F.Cu" "F.Mask" "F.Paste")
			(roundrect_rratio 0.2)
			(net 19 "Net-(D5-C)")
			(pinfunction "C")
			(pintype "passive")
		)
		(pad "2" smd roundrect
			(at 0.7 0 270)
			(size 0.8 1)
			(layers "F.Cu" "F.Mask" "F.Paste")
			(roundrect_rratio 0.2)
			(net 57 "+3V3_TB")
			(pinfunction "A")
			(pintype "passive")
		)
	)
	(footprint "antmicro-footprints:C_0603_1608Metric_EIA"
		(layer "F.Cu")
		(at 129.6 96.25 -90)
		(descr "Capacitor SMD 0603, IPC-7351 Density Level A")
		(tags "Capacitor 0603")
		(property "Reference" "C104"
			(at -9.199999 -38.034999 270)
			(layer "F.SilkS")
			(effects
				(font
					(size 0.7 0.7)
					(thickness 0.15)
				)
			)
		)
		(property "Value" "C_22u_16V_0603"
			(at -1.42757 1.770288 270)
			(layer "F.Fab")
			(effects
				(font
					(size 0.7 0.7)
					(thickness 0.15)
				)
				(justify left bottom)
			)
		)
		(property "Datasheet" "https://product.samsungsem.com/mlcc/CL10A226MO7JZN.do"
			(at 0 0 270)
			(layer "F.Fab")
			(hide yes)
			(effects
				(font
					(size 1.27 1.27)
					(thickness 0.15)
				)
			)
		)
		(property "Description" "SMD Multilayer Ceramic Capacitor"
			(at 0 0 270)
			(layer "F.Fab")
			(hide yes)
			(effects
				(font
					(size 1.27 1.27)
					(thickness 0.15)
				)
			)
		)
		(property "MPN" "CL10A226MO7JZNC"
			(at 0 0 270)
			(unlocked yes)
			(layer "F.Fab")
			(hide yes)
			(effects
				(font
					(size 1 1)
					(thickness 0.15)
				)
			)
		)
		(property "Manufacturer" "Samsung Electro-Mechanics"
			(at 0 0 270)
			(unlocked yes)
			(layer "F.Fab")
			(hide yes)
			(effects
				(font
					(size 1 1)
					(thickness 0.15)
				)
			)
		)
		(property "License" "Apache-2.0"
			(at 0 0 270)
			(unlocked yes)
			(layer "F.Fab")
			(hide yes)
			(effects
				(font
					(size 1 1)
					(thickness 0.15)
				)
			)
		)
		(property "Author" "Antmicro"
			(at 0 0 270)
			(unlocked yes)
			(layer "F.Fab")
			(hide yes)
			(effects
				(font
					(size 1 1)
					(thickness 0.15)
				)
			)
		)
		(property "Val" "22u"
			(at 0 0 270)
			(unlocked yes)
			(layer "F.Fab")
			(hide yes)
			(effects
				(font
					(size 1 1)
					(thickness 0.15)
				)
			)
		)
		(property "Voltage" "16V"
			(at 0 0 270)
			(unlocked yes)
			(layer "F.Fab")
			(hide yes)
			(effects
				(font
					(size 1 1)
					(thickness 0.15)
				)
			)
		)
		(property "Dielectric" ""
			(at 0 0 270)
			(unlocked yes)
			(layer "F.Fab")
			(hide yes)
			(effects
				(font
					(size 1 1)
					(thickness 0.15)
				)
			)
		)
		(sheetname "/X710 DCDC converters/")
		(sheetfile "DCDC_converters_X710.kicad_sch")
		(attr smd)
		(fp_line
			(start -0.15 0.55)
			(end 0.15 0.55)
			(stroke
				(width 0.15)
				(type solid)
			)
			(layer "F.SilkS")
		)
		(fp_line
			(start -0.15 -0.55)
			(end 0.15 -0.55)
			(stroke
				(width 0.15)
				(type solid)
			)
			(layer "F.SilkS")
		)
		(fp_rect
			(start -1.25 -0.65)
			(end 1.25 0.65)
			(stroke
				(width 0.05)
				(type solid)
			)
			(fill no)
			(layer "F.CrtYd")
		)
		(fp_rect
			(start -0.8 -0.45)
			(end 0.8 0.45)
			(stroke
				(width 0.15)
				(type solid)
			)
			(fill no)
			(layer "F.Fab")
		)
		(fp_text user "License: Apache-2.0"
			(at -1.682 5.895 270)
			(layer "F.Fab")
			(effects
				(font
					(size 0.7 0.7)
					(thickness 0.15)
				)
				(justify left bottom)
			)
		)
		(fp_text user "Author: Antmicro"
			(at -1.682 4.894 270)
			(layer "F.Fab")
			(effects
				(font
					(size 0.7 0.7)
					(thickness 0.15)
				)
				(justify left bottom)
			)
		)
		(fp_text user "${REFERENCE}"
			(at -1.682 3.895 270)
			(layer "F.Fab")
			(effects
				(font
					(size 0.7 0.7)
					(thickness 0.15)
				)
				(justify left bottom)
			)
		)
		(pad "1" smd roundrect
			(at -0.7 0 270)
			(size 0.8 1.1)
			(layers "F.Cu" "F.Mask" "F.Paste")
			(roundrect_rratio 0.2)
			(net 23 "GND")
			(pintype "passive")
		)
		(pad "2" smd roundrect
			(at 0.7 0 270)
			(size 0.8 1.1)
			(layers "F.Cu" "F.Mask" "F.Paste")
			(roundrect_rratio 0.2)
			(net 40 "+5V")
			(pintype "passive")
		)
	)
	(footprint "antmicro-footprints:Resonator_SMD_Abracon_ABM8G_3.2x2.5mm"
		(layer "F.Cu")
		(at 130.1 100.9 180)
		(property "Reference" "Y1"
			(at -2.9 -3.1 0)
			(layer "F.SilkS")
			(effects
				(font
					(size 0.7 0.7)
					(thickness 0.15)
				)
			)
		)
		(property "Value" "Resonator_25MHz_ABM8G"
			(at -1.75 2.548 180)
			(layer "F.Fab")
			(effects
				(font
					(size 0.7 0.7)
					(thickness 0.15)
				)
				(justify left bottom)
			)
		)
		(property "Datasheet" "https://abracon.com/Resonators/ABM8G.pdf"
			(at 0 0 180)
			(layer "F.Fab")
			(hide yes)
			(effects
				(font
					(size 1.27 1.27)
					(thickness 0.15)
				)
			)
		)
		(property "Description" "Crystal, 25 MHz, SMD, 3.2mm x 2.5mm, 30 ppm, 18 pF, 20 ppm, ABM8G"
			(at 0 0 180)
			(layer "F.Fab")
			(hide yes)
			(effects
				(font
					(size 1.27 1.27)
					(thickness 0.15)
				)
			)
		)
		(property "MPN" "ABM8G-25.000MHZ-18-D2Y-T3"
			(at 0 0 180)
			(unlocked yes)
			(layer "F.Fab")
			(hide yes)
			(effects
				(font
					(size 1 1)
					(thickness 0.15)
				)
			)
		)
		(property "Manufacturer" "Abracon"
			(at 0 0 180)
			(unlocked yes)
			(layer "F.Fab")
			(hide yes)
			(effects
				(font
					(size 1 1)
					(thickness 0.15)
				)
			)
		)
		(property "License" "Apache-2.0"
			(at 0 0 180)
			(unlocked yes)
			(layer "F.Fab")
			(hide yes)
			(effects
				(font
					(size 1 1)
					(thickness 0.15)
				)
			)
		)
		(property "Author" "Antmicro"
			(at 0 0 180)
			(unlocked yes)
			(layer "F.Fab")
			(hide yes)
			(effects
				(font
					(size 1 1)
					(thickness 0.15)
				)
			)
		)
		(property "Val" "25 MHz"
			(at 0 0 180)
			(unlocked yes)
			(layer "F.Fab")
			(hide yes)
			(effects
				(font
					(size 1 1)
					(thickness 0.15)
				)
			)
		)
		(sheetname "/TB Controller/")
		(sheetfile "tb.kicad_sch")
		(attr smd)
		(fp_line
			(start 1.6 0.3)
			(end 1.6 -0.2)
			(stroke
				(width 0.15)
				(type solid)
			)
			(layer "F.SilkS")
		)
		(fp_line
			(start -0.35 1.25)
			(end 0.45 1.25)
			(stroke
				(width 0.15)
				(type solid)
			)
			(layer "F.SilkS")
		)
		(fp_line
			(start -0.35 -1.25)
			(end 0.45 -1.25)
			(stroke
				(width 0.15)
				(type solid)
			)
			(layer "F.SilkS")
		)
		(fp_line
			(start -1.6 0.3)
			(end -1.6 -0.2)
			(stroke
				(width 0.15)
				(type solid)
			)
			(layer "F.SilkS")
		)
		(fp_circle
			(center -1.75 1.5)
			(end -1.7 1.5)
			(stroke
				(width 0.15)
				(type solid)
			)
			(fill no)
			(layer "F.SilkS")
		)
		(fp_rect
			(start -1.907 -1.55)
			(end 2.006 1.649)
			(stroke
				(width 0.05)
				(type solid)
			)
			(fill no)
			(layer "F.CrtYd")
		)
		(fp_text user "License: Apache-2.0"
			(at -1.75 6.5 180)
			(layer "F.Fab")
			(effects
				(font
					(size 0.7 0.7)
					(thickness 0.15)
				)
				(justify left bottom)
			)
		)
		(fp_text user "${REFERENCE}"
			(at -1.75 3.75 180)
			(layer "F.Fab")
			(effects
				(font
					(size 0.7 0.7)
					(thickness 0.15)
				)
				(justify left bottom)
			)
		)
		(fp_text user "Author: Antmicro"
			(at -1.75 5 180)
			(layer "F.Fab")
			(effects
				(font
					(size 0.7 0.7)
					(thickness 0.15)
				)
				(justify left bottom)
			)
		)
		(pad "1" smd roundrect
			(at -1.101 0.949 180)
			(size 1.3 1.1)
			(layers "F.Cu" "F.Mask" "F.Paste")
			(roundrect_rratio 0)
			(chamfer_ratio 0.2)
			(chamfer bottom_left)
			(net 400 "Net-(U5-XOUT)")
			(pintype "passive")
		)
		(pad "2" smd rect
			(at 1.199 0.949 180)
			(size 1.3 1.1)
			(layers "F.Cu" "F.Mask" "F.Paste")
			(net 23 "GND")
			(pinfunction "SH")
			(pintype "passive")
		)
		(pad "3" smd rect
			(at 1.199 -0.85 180)
			(size 1.3 1.1)
			(layers "F.Cu" "F.Mask" "F.Paste")
			(net 401 "Net-(U5-XIN{slash}CLKIN)")
			(pintype "passive")
		)
		(pad "4" smd rect
			(at -1.101 -0.85 180)
			(size 1.3 1.1)
			(layers "F.Cu" "F.Mask" "F.Paste")
			(net 23 "GND")
			(pinfunction "SH")
			(pintype "passive")
		)
	)
	(footprint "antmicro-footprints:R_0402_1005Metric"
		(layer "F.Cu")
		(at 135 86.25 -90)
		(descr "Resistor SMD 0402")
		(tags "resistor SMD 0402")
		(property "Reference" "R137"
			(at 1.8 4.2 270)
			(layer "F.SilkS")
			(effects
				(font
					(size 0.7 0.7)
					(thickness 0.15)
				)
				(justify left bottom)
			)
		)
		(property "Value" "R_0R_0402"
			(at -1.011843 1.772047 270)
			(layer "F.Fab")
			(effects
				(font
					(size 0.7 0.7)
					(thickness 0.15)
				)
				(justify left bottom)
			)
		)
		(property "Datasheet" "https://industrial.panasonic.com/cdbs/www-data/pdf/RDA0000/AOA0000C301.pdf"
			(at 0 0 270)
			(layer "F.Fab")
			(hide yes)
			(effects
				(font
					(size 1.27 1.27)
					(thickness 0.15)
				)
			)
		)
		(property "Description" "SMD Chip Resistor, Jumper, 0 ohm, 100 mW, 0402 [1005 Metric], Thick Film, General Purpose"
			(at 0 0 270)
			(layer "F.Fab")
			(hide yes)
			(effects
				(font
					(size 1.27 1.27)
					(thickness 0.15)
				)
			)
		)
		(property "MPN" "ERJ2GE0R00X"
			(at 0 0 270)
			(unlocked yes)
			(layer "F.Fab")
			(hide yes)
			(effects
				(font
					(size 1 1)
					(thickness 0.15)
				)
			)
		)
		(property "Manufacturer" "Panasonic"
			(at 0 0 270)
			(unlocked yes)
			(layer "F.Fab")
			(hide yes)
			(effects
				(font
					(size 1 1)
					(thickness 0.15)
				)
			)
		)
		(property "License" "Apache-2.0"
			(at 0 0 270)
			(unlocked yes)
			(layer "F.Fab")
			(hide yes)
			(effects
				(font
					(size 1 1)
					(thickness 0.15)
				)
			)
		)
		(property "Author" "Antmicro"
			(at 0 0 270)
			(unlocked yes)
			(layer "F.Fab")
			(hide yes)
			(effects
				(font
					(size 1 1)
					(thickness 0.15)
				)
			)
		)
		(property "Val" "0R"
			(at 0 0 270)
			(unlocked yes)
			(layer "F.Fab")
			(hide yes)
			(effects
				(font
					(size 1 1)
					(thickness 0.15)
				)
			)
		)
		(property "Tolerance" "~"
			(at 0 0 270)
			(unlocked yes)
			(layer "F.Fab")
			(hide yes)
			(effects
				(font
					(size 1 1)
					(thickness 0.15)
				)
			)
		)
		(property "Current" "1A"
			(at 0 0 270)
			(unlocked yes)
			(layer "F.Fab")
			(hide yes)
			(effects
				(font
					(size 1 1)
					(thickness 0.15)
				)
			)
		)
		(sheetname "/X710-AT2 Misc/")
		(sheetfile "x710-at2-mics.kicad_sch")
		(attr smd)
		(fp_rect
			(start -0.925 -0.47)
			(end 0.925 0.47)
			(stroke
				(width 0.05)
				(type default)
			)
			(fill no)
			(layer "F.CrtYd")
		)
		(fp_rect
			(start -0.5 -0.25)
			(end 0.5 0.25)
			(stroke
				(width 0.15)
				(type solid)
			)
			(fill no)
			(layer "F.Fab")
		)
		(fp_text user "License: Apache-2.0"
			(at -0.95 5.169 270)
			(layer "F.Fab")
			(effects
				(font
					(size 0.7 0.7)
					(thickness 0.15)
				)
				(justify left bottom)
			)
		)
		(fp_text user "${REFERENCE}"
			(at -0.95 3.168 270)
			(layer "F.Fab")
			(effects
				(font
					(size 0.7 0.7)
					(thickness 0.15)
				)
				(justify left bottom)
			)
		)
		(fp_text user "Author: Antmicro"
			(at -0.95 4.169 270)
			(layer "F.Fab")
			(effects
				(font
					(size 0.7 0.7)
					(thickness 0.15)
				)
				(justify left bottom)
			)
		)
		(pad "1" smd roundrect
			(at -0.48 0 270)
			(size 0.59 0.64)
			(layers "F.Cu" "F.Mask" "F.Paste")
			(roundrect_rratio 0.25)
			(net 392 "/TB Controller/~{PE_RST}")
			(pintype "passive")
		)
		(pad "2" smd roundrect
			(at 0.48 0 270)
			(size 0.59 0.64)
			(layers "F.Cu" "F.Mask" "F.Paste")
			(roundrect_rratio 0.25)
			(net 437 "Net-(U15-A)")
			(pintype "passive")
		)
	)
)
